(kicad_pcb
	(version 20241229)
	(generator "pcbnew")
	(generator_version "9.0")
	(general
		(thickness 1.711)
		(legacy_teardrops no)
	)
	(paper "A4")
	(title_block
		(title "Antmicro Baseboard for Jetson AGX Thor")
		(date "2026-02-18")
		(rev "1.1.0")
		(company "Antmicro Ltd")
		(comment 1 "www.antmicro.com")
		(comment 9 "footprint 710 of 1170 (J18), pads 96-188 of 564")
	)
	(layers
		(0 "F.Cu" signal)
		(4 "In1.Cu" signal)
		(6 "In2.Cu" signal)
		(8 "In3.Cu" signal)
		(10 "In4.Cu" jumper)
		(12 "In5.Cu" signal)
		(14 "In6.Cu" signal)
		(16 "In7.Cu" signal)
		(18 "In8.Cu" signal)
		(2 "B.Cu" signal)
		(9 "F.Adhes" user "F.Adhesive")
		(11 "B.Adhes" user "B.Adhesive")
		(13 "F.Paste" user)
		(15 "B.Paste" user)
		(5 "F.SilkS" user "F.Silkscreen")
		(7 "B.SilkS" user "B.Silkscreen")
		(1 "F.Mask" user)
		(3 "B.Mask" user)
		(17 "Dwgs.User" user "User.Drawings")
		(19 "Cmts.User" user "User.Comments")
		(21 "Eco1.User" user "User.Eco1")
		(23 "Eco2.User" user "User.Eco2")
		(25 "Edge.Cuts" user)
		(27 "Margin" user)
		(31 "F.CrtYd" user "F.Courtyard")
		(29 "B.CrtYd" user "B.Courtyard")
		(35 "F.Fab" user)
		(33 "B.Fab" user)
	)
	(footprint "antmicro-footprints:ASP-208571-01_mounting_holes"
		(locked yes)
		(layer "B.Cu")
		(at 77.680532 103.71 90)
		(property "Reference" "J18"
			(at -25.89 11.119468 270)
			(layer "B.SilkS")
			(effects
				(font
					(size 0.7 0.7)
					(thickness 0.15)
				)
				(justify left bottom mirror)
			)
		)
		(property "Value" "ASP-208571-01_mounting_holes"
			(at -15.05 -10.885 270)
			(layer "B.Fab")
			(effects
				(font
					(size 0.7 0.7)
					(thickness 0.15)
				)
				(justify left bottom mirror)
			)
		)
		(property "Datasheet" "https://suddendocs.samtec.com/prints/asp-208571-01-mkt.pdf"
			(at 0 0 270)
			(layer "B.Fab")
			(hide yes)
			(effects
				(font
					(size 1.27 1.27)
					(thickness 0.15)
				)
				(justify mirror)
			)
		)
		(property "Description" "FMC connector"
			(at 0 0 270)
			(layer "B.Fab")
			(hide yes)
			(effects
				(font
					(size 1.27 1.27)
					(thickness 0.15)
				)
				(justify mirror)
			)
		)
		(property "MPN" "ASP-208571-01"
			(at 0 0 90)
			(unlocked yes)
			(layer "B.Fab")
			(hide yes)
			(effects
				(font
					(size 1 1)
					(thickness 0.15)
				)
				(justify mirror)
			)
		)
		(property "Manufacturer" "Samtec"
			(at 0 0 90)
			(unlocked yes)
			(layer "B.Fab")
			(hide yes)
			(effects
				(font
					(size 1 1)
					(thickness 0.15)
				)
				(justify mirror)
			)
		)
		(property "Author" "Antmicro"
			(at 0 0 90)
			(unlocked yes)
			(layer "B.Fab")
			(hide yes)
			(effects
				(font
					(size 1 1)
					(thickness 0.15)
				)
				(justify mirror)
			)
		)
		(property "License" "Apache-2.0"
			(at 0 0 90)
			(unlocked yes)
			(layer "B.Fab")
			(hide yes)
			(effects
				(font
					(size 1 1)
					(thickness 0.15)
				)
				(justify mirror)
			)
		)
		(sheetname "/Expansion connector/")
		(sheetfile "expansion_connector.kicad_sch")
		(attr smd)
		(pad "C12" smd circle
			(at 10.795 3.175 90)
			(size 0.64 0.64)
			(layers "B.Cu" "B.Mask")
			(net 1 "GND")
			(pinfunction "C12")
			(pintype "passive")
		)
		(pad "C13" smd circle
			(at 9.525 3.175 90)
			(size 0.64 0.64)
			(layers "B.Cu" "B.Mask")
			(net 1 "GND")
			(pinfunction "C13")
			(pintype "passive")
		)
		(pad "C14" smd circle
			(at 8.255 3.175 90)
			(size 0.64 0.64)
			(layers "B.Cu" "B.Mask")
			(net 554 "/Expansion connector/PCIe_{C2x1}.~{RST}")
			(pinfunction "C14")
			(pintype "passive")
		)
		(pad "C15" smd circle
			(at 6.985 3.175 90)
			(size 0.64 0.64)
			(layers "B.Cu" "B.Mask")
			(net 694 "/Expansion connector/PCIe_{C2x1}.~{CLKREQ}")
			(pinfunction "C15")
			(pintype "passive")
		)
		(pad "C16" smd circle
			(at 5.715 3.175 90)
			(size 0.64 0.64)
			(layers "B.Cu" "B.Mask")
			(net 1 "GND")
			(pinfunction "C16")
			(pintype "passive")
		)
		(pad "C17" smd circle
			(at 4.445 3.175 90)
			(size 0.64 0.64)
			(layers "B.Cu" "B.Mask")
			(net 1 "GND")
			(pinfunction "C17")
			(pintype "passive")
		)
		(pad "C18" smd circle
			(at 3.175 3.175 90)
			(size 0.64 0.64)
			(layers "B.Cu" "B.Mask")
			(net 781 "/Expansion connector/DP1.HPD")
			(pinfunction "C18")
			(pintype "passive")
		)
		(pad "C19" smd circle
			(at 1.905 3.175 90)
			(size 0.64 0.64)
			(layers "B.Cu" "B.Mask")
			(net 789 "/Expansion connector/DP2.HPD")
			(pinfunction "C19")
			(pintype "passive")
		)
		(pad "C20" smd circle
			(at 0.635 3.175 90)
			(size 0.64 0.64)
			(layers "B.Cu" "B.Mask")
			(net 1 "GND")
			(pinfunction "C20")
			(pintype "passive")
		)
		(pad "C21" smd circle
			(at -0.635 3.175 90)
			(size 0.64 0.64)
			(layers "B.Cu" "B.Mask")
			(net 1 "GND")
			(pinfunction "C21")
			(pintype "passive")
		)
		(pad "C22" smd circle
			(at -1.905 3.175 90)
			(size 0.64 0.64)
			(layers "B.Cu" "B.Mask")
			(net 574 "/Expansion connector/DP3.HPD")
			(pinfunction "C22")
			(pintype "passive")
		)
		(pad "C23" smd circle
			(at -3.175 3.175 90)
			(size 0.64 0.64)
			(layers "B.Cu" "B.Mask")
			(net 321 "/Expansion connector/GPIO.MCLK03")
			(pinfunction "C23")
			(pintype "passive")
		)
		(pad "C24" smd circle
			(at -4.445 3.175 90)
			(size 0.64 0.64)
			(layers "B.Cu" "B.Mask")
			(net 1 "GND")
			(pinfunction "C24")
			(pintype "passive")
		)
		(pad "C25" smd circle
			(at -5.715 3.175 90)
			(size 0.64 0.64)
			(layers "B.Cu" "B.Mask")
			(net 1 "GND")
			(pinfunction "C25")
			(pintype "passive")
		)
		(pad "C26" smd circle
			(at -6.985 3.175 90)
			(size 0.64 0.64)
			(layers "B.Cu" "B.Mask")
			(net 368 "/Expansion connector/GPIO.21")
			(pinfunction "C26")
			(pintype "passive")
		)
		(pad "C27" smd circle
			(at -8.255 3.175 90)
			(size 0.64 0.64)
			(layers "B.Cu" "B.Mask")
			(net 861 "/Expansion connector/GPIO.27")
			(pinfunction "C27")
			(pintype "passive")
		)
		(pad "C28" smd circle
			(at -9.525 3.175 90)
			(size 0.64 0.64)
			(layers "B.Cu" "B.Mask")
			(net 1 "GND")
			(pinfunction "C28")
			(pintype "passive")
		)
		(pad "C29" smd circle
			(at -10.795 3.175 90)
			(size 0.64 0.64)
			(layers "B.Cu" "B.Mask")
			(net 1 "GND")
			(pinfunction "C29")
			(pintype "passive")
		)
		(pad "C30" smd circle
			(at -12.065 3.175 90)
			(size 0.64 0.64)
			(layers "B.Cu" "B.Mask")
			(net 407 "/Expansion connector/I2C0.SCL")
			(pinfunction "C30")
			(pintype "passive")
		)
		(pad "C31" smd circle
			(at -13.335 3.175 90)
			(size 0.64 0.64)
			(layers "B.Cu" "B.Mask")
			(net 561 "/Expansion connector/I2C0.SDA")
			(pinfunction "C31")
			(pintype "passive")
		)
		(pad "C32" smd circle
			(at -14.605 3.175 90)
			(size 0.64 0.64)
			(layers "B.Cu" "B.Mask")
			(net 1 "GND")
			(pinfunction "C32")
			(pintype "passive")
		)
		(pad "C33" smd circle
			(at -15.875 3.175 90)
			(size 0.64 0.64)
			(layers "B.Cu" "B.Mask")
			(net 1 "GND")
			(pinfunction "C33")
			(pintype "passive")
		)
		(pad "C34" smd circle
			(at -17.145 3.175 90)
			(size 0.64 0.64)
			(layers "B.Cu" "B.Mask")
			(net 677 "/Expansion connector/ADDR0")
			(pinfunction "C34")
			(pintype "passive")
		)
		(pad "C35" smd circle
			(at -18.415 3.175 90)
			(size 0.64 0.64)
			(layers "B.Cu" "B.Mask")
			(net 289 "/Expansion connector/+12V_FMC")
			(pinfunction "C35")
			(pintype "passive")
		)
		(pad "C36" smd circle
			(at -19.685 3.175 90)
			(size 0.64 0.64)
			(layers "B.Cu" "B.Mask")
			(net 1 "GND")
			(pinfunction "C36")
			(pintype "passive")
		)
		(pad "C37" smd circle
			(at -20.955 3.175 90)
			(size 0.64 0.64)
			(layers "B.Cu" "B.Mask")
			(net 289 "/Expansion connector/+12V_FMC")
			(pinfunction "C37")
			(pintype "passive")
		)
		(pad "C38" smd circle
			(at -22.225 3.175 90)
			(size 0.64 0.64)
			(layers "B.Cu" "B.Mask")
			(net 1 "GND")
			(pinfunction "C38")
			(pintype "passive")
		)
		(pad "C39" smd circle
			(at -23.495 3.175 90)
			(size 0.64 0.64)
			(layers "B.Cu" "B.Mask")
			(net 297 "/Expansion connector/+3V3_FMC")
			(pinfunction "C39")
			(pintype "passive")
		)
		(pad "C40" smd circle
			(at -24.765 3.175 90)
			(size 0.64 0.64)
			(layers "B.Cu" "B.Mask")
			(net 1 "GND")
			(pinfunction "C40")
			(pintype "passive")
		)
		(pad "D01" smd circle
			(at 24.765 1.905 90)
			(size 0.64 0.64)
			(layers "B.Cu" "B.Mask")
			(net 342 "/Expansion connector/FMC_PG_C2M")
			(pinfunction "D01")
			(pintype "passive")
		)
		(pad "D02" smd circle
			(at 23.495 1.905 90)
			(size 0.64 0.64)
			(layers "B.Cu" "B.Mask")
			(net 1 "GND")
			(pinfunction "D02")
			(pintype "passive")
		)
		(pad "D03" smd circle
			(at 22.225 1.905 90)
			(size 0.64 0.64)
			(layers "B.Cu" "B.Mask")
			(net 1 "GND")
			(pinfunction "D03")
			(pintype "passive")
		)
		(pad "D04" smd circle
			(at 20.955 1.905 90)
			(size 0.64 0.64)
			(layers "B.Cu" "B.Mask")
			(net 434 "unconnected-(J18-PadD04)")
			(pinfunction "D04")
			(pintype "passive+no_connect")
		)
		(pad "D05" smd circle
			(at 19.685 1.905 90)
			(size 0.64 0.64)
			(layers "B.Cu" "B.Mask")
			(net 309 "unconnected-(J18-PadD05)")
			(pinfunction "D05")
			(pintype "passive+no_connect")
		)
		(pad "D06" smd circle
			(at 18.415 1.905 90)
			(size 0.64 0.64)
			(layers "B.Cu" "B.Mask")
			(net 1 "GND")
			(pinfunction "D06")
			(pintype "passive")
		)
		(pad "D07" smd circle
			(at 17.145 1.905 90)
			(size 0.64 0.64)
			(layers "B.Cu" "B.Mask")
			(net 1 "GND")
			(pinfunction "D07")
			(pintype "passive")
		)
		(pad "D08" smd circle
			(at 15.875 1.905 90)
			(size 0.64 0.64)
			(layers "B.Cu" "B.Mask")
			(net 82 "/Expansion connector/UART2.RTS")
			(pinfunction "D08")
			(pintype "passive")
		)
		(pad "D09" smd circle
			(at 14.605 1.905 90)
			(size 0.64 0.64)
			(layers "B.Cu" "B.Mask")
			(net 158 "/Expansion connector/UART2.CTS")
			(pinfunction "D09")
			(pintype "passive")
		)
		(pad "D10" smd circle
			(at 13.335 1.905 90)
			(size 0.64 0.64)
			(layers "B.Cu" "B.Mask")
			(net 1 "GND")
			(pinfunction "D10")
			(pintype "passive")
		)
		(pad "D11" smd circle
			(at 12.065 1.905 90)
			(size 0.64 0.64)
			(layers "B.Cu" "B.Mask")
			(net 61 "/Expansion connector/UART2.TX")
			(pinfunction "D11")
			(pintype "passive")
		)
		(pad "D12" smd circle
			(at 10.795 1.905 90)
			(size 0.64 0.64)
			(layers "B.Cu" "B.Mask")
			(net 51 "/Expansion connector/UART2.RX")
			(pinfunction "D12")
			(pintype "passive")
		)
		(pad "D13" smd circle
			(at 9.525 1.905 90)
			(size 0.64 0.64)
			(layers "B.Cu" "B.Mask")
			(net 1 "GND")
			(pinfunction "D13")
			(pintype "passive")
		)
		(pad "D14" smd circle
			(at 8.255 1.905 90)
			(size 0.64 0.64)
			(layers "B.Cu" "B.Mask")
			(net 56 "/Expansion connector/UART5.RTS")
			(pinfunction "D14")
			(pintype "passive")
		)
		(pad "D15" smd circle
			(at 6.985 1.905 90)
			(size 0.64 0.64)
			(layers "B.Cu" "B.Mask")
			(net 121 "/Expansion connector/UART5.CTS")
			(pinfunction "D15")
			(pintype "passive")
		)
		(pad "D16" smd circle
			(at 5.715 1.905 90)
			(size 0.64 0.64)
			(layers "B.Cu" "B.Mask")
			(net 1 "GND")
			(pinfunction "D16")
			(pintype "passive")
		)
		(pad "D17" smd circle
			(at 4.445 1.905 90)
			(size 0.64 0.64)
			(layers "B.Cu" "B.Mask")
			(net 118 "/Expansion connector/UART5.TX")
			(pinfunction "D17")
			(pintype "passive")
		)
		(pad "D18" smd circle
			(at 3.175 1.905 90)
			(size 0.64 0.64)
			(layers "B.Cu" "B.Mask")
			(net 151 "/Expansion connector/UART5.RX")
			(pinfunction "D18")
			(pintype "passive")
		)
		(pad "D19" smd circle
			(at 1.905 1.905 90)
			(size 0.64 0.64)
			(layers "B.Cu" "B.Mask")
			(net 1 "GND")
			(pinfunction "D19")
			(pintype "passive")
		)
		(pad "D20" smd circle
			(at 0.635 1.905 90)
			(size 0.64 0.64)
			(layers "B.Cu" "B.Mask")
			(net 850 "/I2C_{SYS}.SDA")
			(pinfunction "D20")
			(pintype "passive")
		)
		(pad "D21" smd circle
			(at -0.635 1.905 90)
			(size 0.64 0.64)
			(layers "B.Cu" "B.Mask")
			(net 853 "/I2C_{SYS}.SCL")
			(pinfunction "D21")
			(pintype "passive")
		)
		(pad "D22" smd circle
			(at -1.905 1.905 90)
			(size 0.64 0.64)
			(layers "B.Cu" "B.Mask")
			(net 1 "GND")
			(pinfunction "D22")
			(pintype "passive")
		)
		(pad "D23" smd circle
			(at -3.175 1.905 90)
			(size 0.64 0.64)
			(layers "B.Cu" "B.Mask")
			(net 842 "/Expansion connector/I2C7.SDA")
			(pinfunction "D23")
			(pintype "passive")
		)
		(pad "D24" smd circle
			(at -4.445 1.905 90)
			(size 0.64 0.64)
			(layers "B.Cu" "B.Mask")
			(net 866 "/Expansion connector/I2C7.SCL")
			(pinfunction "D24")
			(pintype "passive")
		)
		(pad "D25" smd circle
			(at -5.715 1.905 90)
			(size 0.64 0.64)
			(layers "B.Cu" "B.Mask")
			(net 1 "GND")
			(pinfunction "D25")
			(pintype "passive")
		)
		(pad "D26" smd circle
			(at -6.985 1.905 90)
			(size 0.64 0.64)
			(layers "B.Cu" "B.Mask")
			(net 857 "/Expansion connector/I2C8.SCL")
			(pinfunction "D26")
			(pintype "passive")
		)
		(pad "D27" smd circle
			(at -8.255 1.905 90)
			(size 0.64 0.64)
			(layers "B.Cu" "B.Mask")
			(net 856 "/Expansion connector/I2C8.SDA")
			(pinfunction "D27")
			(pintype "passive")
		)
		(pad "D28" smd circle
			(at -9.525 1.905 90)
			(size 0.64 0.64)
			(layers "B.Cu" "B.Mask")
			(net 1 "GND")
			(pinfunction "D28")
			(pintype "passive")
		)
		(pad "D29" smd circle
			(at -10.795 1.905 90)
			(size 0.64 0.64)
			(layers "B.Cu" "B.Mask")
			(net 655 "unconnected-(J18-PadD29)")
			(pinfunction "D29")
			(pintype "passive+no_connect")
		)
		(pad "D30" smd circle
			(at -12.065 1.905 90)
			(size 0.64 0.64)
			(layers "B.Cu" "B.Mask")
			(net 449 "unconnected-(J18-PadD30)")
			(pinfunction "D30")
			(pintype "passive+no_connect")
		)
		(pad "D31" smd circle
			(at -13.335 1.905 90)
			(size 0.64 0.64)
			(layers "B.Cu" "B.Mask")
			(net 383 "unconnected-(J18-PadD31)")
			(pinfunction "D31")
			(pintype "passive+no_connect")
		)
		(pad "D32" smd circle
			(at -14.605 1.905 90)
			(size 0.64 0.64)
			(layers "B.Cu" "B.Mask")
			(net 148 "/Expansion connector/+3V3_AUX")
			(pinfunction "D32")
			(pintype "passive")
		)
		(pad "D33" smd circle
			(at -15.875 1.905 90)
			(size 0.64 0.64)
			(layers "B.Cu" "B.Mask")
			(net 484 "unconnected-(J18-PadD33)")
			(pinfunction "D33")
			(pintype "passive+no_connect")
		)
		(pad "D34" smd circle
			(at -17.145 1.905 90)
			(size 0.64 0.64)
			(layers "B.Cu" "B.Mask")
			(net 384 "unconnected-(J18-PadD34)")
			(pinfunction "D34")
			(pintype "passive+no_connect")
		)
		(pad "D35" smd circle
			(at -18.415 1.905 90)
			(size 0.64 0.64)
			(layers "B.Cu" "B.Mask")
			(net 472 "/Expansion connector/ADDR1")
			(pinfunction "D35")
			(pintype "passive")
		)
		(pad "D36" smd circle
			(at -19.685 1.905 90)
			(size 0.64 0.64)
			(layers "B.Cu" "B.Mask")
			(net 297 "/Expansion connector/+3V3_FMC")
			(pinfunction "D36")
			(pintype "passive")
		)
		(pad "D37" smd circle
			(at -20.955 1.905 90)
			(size 0.64 0.64)
			(layers "B.Cu" "B.Mask")
			(net 1 "GND")
			(pinfunction "D37")
			(pintype "passive")
		)
		(pad "D38" smd circle
			(at -22.225 1.905 90)
			(size 0.64 0.64)
			(layers "B.Cu" "B.Mask")
			(net 297 "/Expansion connector/+3V3_FMC")
			(pinfunction "D38")
			(pintype "passive")
		)
		(pad "D39" smd circle
			(at -23.495 1.905 90)
			(size 0.64 0.64)
			(layers "B.Cu" "B.Mask")
			(net 1 "GND")
			(pinfunction "D39")
			(pintype "passive")
		)
		(pad "D40" smd circle
			(at -24.765 1.905 90)
			(size 0.64 0.64)
			(layers "B.Cu" "B.Mask")
			(net 297 "/Expansion connector/+3V3_FMC")
			(pinfunction "D40")
			(pintype "passive")
		)
		(pad "E01" smd circle
			(at 24.765 0.635 90)
			(size 0.64 0.64)
			(layers "B.Cu" "B.Mask")
			(net 1 "GND")
			(pinfunction "E01")
			(pintype "passive")
		)
		(pad "E02" smd circle
			(at 23.495 0.635 90)
			(size 0.64 0.64)
			(layers "B.Cu" "B.Mask")
			(net 865 "unconnected-(J18-PadE02)")
			(pinfunction "E02")
			(pintype "passive+no_connect")
		)
		(pad "E03" smd circle
			(at 22.225 0.635 90)
			(size 0.64 0.64)
			(layers "B.Cu" "B.Mask")
			(net 860 "unconnected-(J18-PadE03)")
			(pinfunction "E03")
			(pintype "passive+no_connect")
		)
		(pad "E04" smd circle
			(at 20.955 0.635 90)
			(size 0.64 0.64)
			(layers "B.Cu" "B.Mask")
			(net 1 "GND")
			(pinfunction "E04")
			(pintype "passive")
		)
		(pad "E05" smd circle
			(at 19.685 0.635 90)
			(size 0.64 0.64)
			(layers "B.Cu" "B.Mask")
			(net 1 "GND")
			(pinfunction "E05")
			(pintype "passive")
		)
		(pad "E06" smd circle
			(at 18.415 0.635 90)
			(size 0.64 0.64)
			(layers "B.Cu" "B.Mask")
			(net 858 "unconnected-(J18-PadE06)")
			(pinfunction "E06")
			(pintype "passive+no_connect")
		)
		(pad "E07" smd circle
			(at 17.145 0.635 90)
			(size 0.64 0.64)
			(layers "B.Cu" "B.Mask")
			(net 854 "unconnected-(J18-PadE07)")
			(pinfunction "E07")
			(pintype "passive+no_connect")
		)
		(pad "E08" smd circle
			(at 15.875 0.635 90)
			(size 0.64 0.64)
			(layers "B.Cu" "B.Mask")
			(net 1 "GND")
			(pinfunction "E08")
			(pintype "passive")
		)
		(pad "E09" smd circle
			(at 14.605 0.635 90)
			(size 0.64 0.64)
			(layers "B.Cu" "B.Mask")
			(net 288 "unconnected-(J18-PadE09)")
			(pinfunction "E09")
			(pintype "passive+no_connect")
		)
		(pad "E10" smd circle
			(at 13.335 0.635 90)
			(size 0.64 0.64)
			(layers "B.Cu" "B.Mask")
			(net 844 "unconnected-(J18-PadE10)")
			(pinfunction "E10")
			(pintype "passive+no_connect")
		)
		(pad "E11" smd circle
			(at 12.065 0.635 90)
			(size 0.64 0.64)
			(layers "B.Cu" "B.Mask")
			(net 1 "GND")
			(pinfunction "E11")
			(pintype "passive")
		)
		(pad "E12" smd circle
			(at 10.795 0.635 90)
			(size 0.64 0.64)
			(layers "B.Cu" "B.Mask")
			(net 385 "unconnected-(J18-PadE12)")
			(pinfunction "E12")
			(pintype "passive+no_connect")
		)
		(pad "E13" smd circle
			(at 9.525 0.635 90)
			(size 0.64 0.64)
			(layers "B.Cu" "B.Mask")
			(net 346 "unconnected-(J18-PadE13)")
			(pinfunction "E13")
			(pintype "passive+no_connect")
		)
		(pad "E14" smd circle
			(at 8.255 0.635 90)
			(size 0.64 0.64)
			(layers "B.Cu" "B.Mask")
			(net 1 "GND")
			(pinfunction "E14")
			(pintype "passive")
		)
		(pad "E15" smd circle
			(at 6.985 0.635 90)
			(size 0.64 0.64)
			(layers "B.Cu" "B.Mask")
			(net 863 "unconnected-(J18-PadE15)")
			(pinfunction "E15")
			(pintype "passive+no_connect")
		)
		(pad "E16" smd circle
			(at 5.715 0.635 90)
			(size 0.64 0.64)
			(layers "B.Cu" "B.Mask")
			(net 381 "unconnected-(J18-PadE16)")
			(pinfunction "E16")
			(pintype "passive+no_connect")
		)
		(pad "E17" smd circle
			(at 4.445 0.635 90)
			(size 0.64 0.64)
			(layers "B.Cu" "B.Mask")
			(net 1 "GND")
			(pinfunction "E17")
			(pintype "passive")
		)
		(pad "E18" smd circle
			(at 3.175 0.635 90)
			(size 0.64 0.64)
			(layers "B.Cu" "B.Mask")
			(net 862 "unconnected-(J18-PadE18)")
			(pinfunction "E18")
			(pintype "passive+no_connect")
		)
		(pad "E19" smd circle
			(at 1.905 0.635 90)
			(size 0.64 0.64)
			(layers "B.Cu" "B.Mask")
			(net 848 "unconnected-(J18-PadE19)")
			(pinfunction "E19")
			(pintype "passive+no_connect")
		)
		(pad "E20" smd circle
			(at 0.635 0.635 90)
			(size 0.64 0.64)
			(layers "B.Cu" "B.Mask")
			(net 1 "GND")
			(pinfunction "E20")
			(pintype "passive")
		)
		(pad "E21" smd circle
			(at -0.635 0.635 90)
			(size 0.64 0.64)
			(layers "B.Cu" "B.Mask")
			(net 437 "unconnected-(J18-PadE21)")
			(pinfunction "E21")
			(pintype "passive+no_connect")
		)
		(pad "E22" smd circle
			(at -1.905 0.635 90)
			(size 0.64 0.64)
			(layers "B.Cu" "B.Mask")
			(net 840 "unconnected-(J18-PadE22)")
			(pinfunction "E22")
			(pintype "passive+no_connect")
		)
		(pad "E23" smd circle
			(at -3.175 0.635 90)
			(size 0.64 0.64)
			(layers "B.Cu" "B.Mask")
			(net 1 "GND")
			(pinfunction "E23")
			(pintype "passive")
		)
		(pad "E24" smd circle
			(at -4.445 0.635 90)
			(size 0.64 0.64)
			(layers "B.Cu" "B.Mask")
			(net 446 "unconnected-(J18-PadE24)")
			(pinfunction "E24")
			(pintype "passive+no_connect")
		)
	)
)
